# T6G (Grand Teton) — schematic netlist excerpt (pin names and nets, part order shuffled) for the footprints in the layout excerpt that follows; sources: Cadence DE-HDL packaged netlist, KiCad conversion of 04192023_DAF0TMB3IC0_F0TG_MB_C_brd_V02_OCP.brd

U55  ISL28022FRZT  ISL28022FRZ-T IC  pkg QFN16_TH_0-5_3X3XH  page 357
  A1  = INA230_6_A1
  A0  = INA230_6_A0
  \ext_clk||int\  = P12V_OCP_SFF_ADC_ALERT_R
  \sda||smbdat\  = SMB_INA230_6_3V3AUX_SDA_R1
  \scl|||smbclk\  = SMB_INA230_6_3V3AUX_SCL_R1
  NC0  = NC_INA230_6_NC0
  NC1  = NC_INA230_6_NC1
  NC2  = NC_INA230_6_NC2
  VCC  = P3V3_AUX
  GND  = GND
  VBUS  = P12V_OCP_SFF
  VINM  = VSENSE_P12V_INA230_6_INN
  VINP  = VSENSE_P12V_INA230_6_INP
  NC3  = NC_INA230_6_NC3
  NC4  = NC_INA230_6_NC4
  NC5  = NC_INA230_6_NC5
  TH_GND  = GND

(kicad_pcb
	(version 20260206)
	(generator "pcbnew")
	(generator_version "10.0")
	(general
		(thickness 1.6)
		(legacy_teardrops no)
	)
	(paper "A4")
	(title_block
		(title "04192023_DAF0TMB3IC0_F0TG_MB_C_brd_V02_OCP.brd")
		(comment 1 "Grand Teton / footprints 2992-2992 of 8354")
	)
	(layers
		(0 "F.Cu" signal "TOP")
		(4 "In1.Cu" signal "GND")
		(6 "In2.Cu" signal "IN1")
		(8 "In3.Cu" signal "GND1")
		(10 "In4.Cu" signal "IN2")
		(12 "In5.Cu" signal "GND2")
		(14 "In6.Cu" signal "IN3")
		(16 "In7.Cu" signal "GND3")
		(18 "In8.Cu" signal "VCC")
		(20 "In9.Cu" signal "VCC1")
		(22 "In10.Cu" signal "GND4")
		(24 "In11.Cu" signal "IN4")
		(26 "In12.Cu" signal "GND5")
		(28 "In13.Cu" signal "IN5")
		(30 "In14.Cu" signal "GND6")
		(32 "In15.Cu" signal "IN6")
		(34 "In16.Cu" signal "GND7")
		(2 "B.Cu" signal "BOTTOM")
		(9 "F.Adhes" user "F.Adhesive")
		(11 "B.Adhes" user "B.Adhesive")
		(13 "F.Paste" user "Package Geometry/Pastemask Top")
		(15 "B.Paste" user "Package Geometry/Pastemask Bottom")
		(5 "F.SilkS" user "Ref Des/Silkscreen Top")
		(7 "B.SilkS" user "Ref Des/Silkscreen Bottom")
		(1 "F.Mask" user "Board Geometry/Soldermask Top")
		(3 "B.Mask" user "Board Geometry/Soldermask Bottom")
		(17 "Dwgs.User" user "User.Drawings")
		(19 "Cmts.User" user "User.Comments")
		(21 "Eco1.User" user "User.Eco1")
		(23 "Eco2.User" user "User.Eco2")
		(25 "Edge.Cuts" user "Board Geometry/Outline")
		(27 "Margin" user)
		(31 "F.CrtYd" user "Package Geometry/Place Bound Top")
		(29 "B.CrtYd" user "Package Geometry/Place Bound Bottom")
		(35 "F.Fab" user "Ref Des/Assembly Top")
		(33 "B.Fab" user "Ref Des/Assembly Bottom")
	)
	(footprint ""
		(layer "F.Cu")
		(at 395.279118 -76.305664)
		(property "Reference" "U55"
			(at -0.526288 -4.18084 0)
			(unlocked yes)
			(layer "F.SilkS")
			(effects
				(font
					(size 0.7874 0.5842)
					(thickness 0.1524)
				)
			)
		)
		(property "Value" ""
			(at 0 0 0)
			(layer "F.Fab")
			(effects
				(font
					(size 1.27 1.27)
				)
			)
		)
		(duplicate_pad_numbers_are_jumpers no)
		(fp_line
			(start -1.500124 -1.500124)
			(end -1.004062 -1.500124)
			(stroke
				(width 0.1524)
				(type default)
			)
			(layer "F.SilkS")
		)
		(fp_line
			(start -1.500124 -1.004062)
			(end -1.500124 -1.500124)
			(stroke
				(width 0.1524)
				(type default)
			)
			(layer "F.SilkS")
		)
		(fp_line
			(start -1.500124 1.500124)
			(end -1.500124 1.004062)
			(stroke
				(width 0.1524)
				(type default)
			)
			(layer "F.SilkS")
		)
		(fp_line
			(start -1.004062 1.500124)
			(end -1.500124 1.500124)
			(stroke
				(width 0.1524)
				(type default)
			)
			(layer "F.SilkS")
		)
		(fp_line
			(start 1.004062 -1.500124)
			(end 1.500124 -1.500124)
			(stroke
				(width 0.1524)
				(type default)
			)
			(layer "F.SilkS")
		)
		(fp_line
			(start 1.500124 -1.500124)
			(end 1.500124 -1.004062)
			(stroke
				(width 0.1524)
				(type default)
			)
			(layer "F.SilkS")
		)
		(fp_line
			(start 1.500124 1.004062)
			(end 1.500124 1.500124)
			(stroke
				(width 0.1524)
				(type default)
			)
			(layer "F.SilkS")
		)
		(fp_line
			(start 1.500124 1.500124)
			(end 1.004062 1.500124)
			(stroke
				(width 0.1524)
				(type default)
			)
			(layer "F.SilkS")
		)
		(fp_poly
			(pts
				(xy -1.271016 -2.21869) (xy -2.285238 -2.159254) (xy -1.718564 -1.17475)
			)
			(stroke
				(width 0)
				(type default)
			)
			(fill yes)
			(layer "F.SilkS")
		)
		(fp_line
			(start -1.500124 -1.500124)
			(end 1.500124 -1.500124)
			(stroke
				(width 0.1)
				(type default)
			)
			(layer "F.Fab")
		)
		(fp_line
			(start -1.500124 1.500124)
			(end -1.500124 -1.500124)
			(stroke
				(width 0.1)
				(type default)
			)
			(layer "F.Fab")
		)
		(fp_line
			(start 1.500124 -1.500124)
			(end 1.500124 1.500124)
			(stroke
				(width 0.1)
				(type default)
			)
			(layer "F.Fab")
		)
		(fp_line
			(start 1.500124 1.500124)
			(end -1.500124 1.500124)
			(stroke
				(width 0.1)
				(type default)
			)
			(layer "F.Fab")
		)
		(fp_poly
			(pts
				(xy -2.847848 -1.258062) (xy -2.847848 -0.242062) (xy -1.831848 -0.750062)
			)
			(stroke
				(width 0)
				(type default)
			)
			(fill yes)
			(layer "F.Fab")
		)
		(pad "1" smd rect
			(at -1.400048 -0.750062 270)
			(size 0.2286 0.6096)
			(layers "F.Cu" "F.Mask" "F.Paste")
			(net "INA230_6_A1")
		)
		(pad "2" smd rect
			(at -1.400048 -0.249936 270)
			(size 0.2286 0.6096)
			(layers "F.Cu" "F.Mask" "F.Paste")
			(net "INA230_6_A0")
		)
		(pad "3" smd rect
			(at -1.400048 0.249936 270)
			(size 0.2286 0.6096)
			(layers "F.Cu" "F.Mask" "F.Paste")
			(net "P12V_OCP_SFF_ADC_ALERT_R")
		)
		(pad "4" smd rect
			(at -1.400048 0.750062 270)
			(size 0.2286 0.6096)
			(layers "F.Cu" "F.Mask" "F.Paste")
			(net "SMB_INA230_6_3V3AUX_SDA_R1")
		)
		(pad "5" smd rect
			(at -0.750062 1.400048)
			(size 0.2286 0.6096)
			(layers "F.Cu" "F.Mask" "F.Paste")
			(net "SMB_INA230_6_3V3AUX_SCL_R1")
		)
		(pad "6" smd rect
			(at -0.249936 1.400048)
			(size 0.2286 0.6096)
			(layers "F.Cu" "F.Mask" "F.Paste")
			(net "NC_INA230_6_NC0")
		)
		(pad "7" smd rect
			(at 0.249936 1.400048)
			(size 0.2286 0.6096)
			(layers "F.Cu" "F.Mask" "F.Paste")
			(net "NC_INA230_6_NC1")
		)
		(pad "8" smd rect
			(at 0.750062 1.400048)
			(size 0.2286 0.6096)
			(layers "F.Cu" "F.Mask" "F.Paste")
			(net "NC_INA230_6_NC2")
		)
		(pad "9" smd rect
			(at 1.400048 0.750062 270)
			(size 0.2286 0.6096)
			(layers "F.Cu" "F.Mask" "F.Paste")
			(net "P3V3_AUX")
		)
		(pad "10" smd rect
			(at 1.400048 0.249936 270)
			(size 0.2286 0.6096)
			(layers "F.Cu" "F.Mask" "F.Paste")
			(net "GND")
		)
		(pad "11" smd rect
			(at 1.400048 -0.249936 270)
			(size 0.2286 0.6096)
			(layers "F.Cu" "F.Mask" "F.Paste")
			(net "P12V_OCP_SFF")
		)
		(pad "12" smd rect
			(at 1.400048 -0.750062 270)
			(size 0.2286 0.6096)
			(layers "F.Cu" "F.Mask" "F.Paste")
			(net "VSENSE_P12V_INA230_6_INN")
		)
		(pad "13" smd rect
			(at 0.750062 -1.400048)
			(size 0.2286 0.6096)
			(layers "F.Cu" "F.Mask" "F.Paste")
			(net "VSENSE_P12V_INA230_6_INP")
		)
		(pad "14" smd rect
			(at 0.249936 -1.400048)
			(size 0.2286 0.6096)
			(layers "F.Cu" "F.Mask" "F.Paste")
			(net "NC_INA230_6_NC3")
		)
		(pad "15" smd rect
			(at -0.249936 -1.400048)
			(size 0.2286 0.6096)
			(layers "F.Cu" "F.Mask" "F.Paste")
			(net "NC_INA230_6_NC4")
		)
		(pad "16" smd rect
			(at -0.750062 -1.400048)
			(size 0.2286 0.6096)
			(layers "F.Cu" "F.Mask" "F.Paste")
			(net "NC_INA230_6_NC5")
		)
		(pad "TH" smd rect
			(at 0 0)
			(size 1.7018 1.7018)
			(layers "F.Cu" "F.Mask" "F.Paste")
			(net "GND")
		)
		(zone
			(layer "F.Cu")
			(hatch none 0.5)
			(connect_pads
				(clearance 0)
			)
			(min_thickness 0.25)
			(keepout
				(tracks not_allowed)
				(vias allowed)
				(pads allowed)
				(copperpour not_allowed)
				(footprints allowed)
			)
			(placement
				(enabled no)
				(sheetname "")
			)
			(fill
				(thermal_gap 0.5)
				(thermal_bridge_width 0.5)
				(island_removal_mode 0)
			)
			(polygon
				(pts
					(xy 394.23467 -76.331064) (xy 394.23467 -77.350112) (xy 396.323566 -77.350112) (xy 396.323566 -75.261216)
					(xy 394.23467 -75.261216) (xy 394.23467 -76.305664) (xy 394.377418 -76.305664) (xy 394.377418 -75.403964)
					(xy 396.180818 -75.403964) (xy 396.180818 -77.207364) (xy 394.377418 -77.207364) (xy 394.377418 -76.331064)
				)
			)
		)
	)
)
